Quanta Computer Inc.
1
Design Files Contribution
For Meta Grand Teton System



2
➢ Grand Teton System Spec
➢ Grand Teton System Overview
➢ CPU Tray Overview
➢ Switch Tray Overview
➢ System boards Introduction
Agenda



Grand Teton Specification
3
Grand Teton Platform Specification(Version 1.0)
https://www.opencompute.org/documents/grand-teton-platform-specification-v1-0-pdf


Grand Teton System Overview
4



8OU Chassis Dimension: 537mm (W) x 381mm (H) x 800mm(D)
Grand Teton System Overview
5
381 mm
4OU Accelerator Tray
2OU CPU Tray
2OU Switch Tray



6
8x OCP NIC 3.0
(TSFF)
4OU Accelerator Tray
2OU CPU Tray
2OU Switch Tray
8x E1.S
2x OCP NIC 3.0
(TSFF)
1x E1.S DC-SCM 1.0
8x GPU
Grand Teton System Front view



7
3x Bus Bar Clip
16x 8056 fan
Grand Teton System Rear View



8
4OU Accelerator Tray
2OU CPU Tray
2OU Switch Tray
Grand Teton Placement Side View



9
8056 fan *16
Explosion Orientation
4OU Accelerator Tray
2OU MB Tray
2OU Switch Tray
HPDB*1
Fan board*2
Grand Teton Chassis
3x Bus Bar Clip
CPU board*1
DC-SCM*1
Switch board*1
FIO board*1
GPU baseboard
CPU w/CPU HS*2
M.2 SSD*1
E1.S SSD*8
OCP NIC 3.0 *2
E1.S SSD*16
OCP NIC 3.0 *8
GPU*8
VPDB*1
Rear Top Cover
Grand Teton System Exploded View



CPU Tray Introduction
10



11
95mm
2OU CPU Tray Dimension: 502mm (W) x 95mm (H) x 560mm(D)
CPU Tray Overview



12
2x OCP NIC 3.0
(TSFF)
1x E1.S
2x CPU w/ Remote HS
Intel: 32x DIMM
AMD: 24x DIMM
2x OCP NIC 3.0
(TSFF)
DC-SCM 1.0
DC-SCM 1.0
1x E1.S
M.2 , support 
2280/22110
CPU Tray Front and Top View



13
Item Description
CPU Board
• 2 socket CPU TDP
o Intel: Sapphire Rapids CPU Up to 350W per CPU
o AMD: Genoa CPU Up to 400W per CPU
• Memory
o Intel: Each CPU supports 8 DDR5 memory channels, 2DPC, up to 32 DIMMs in total
o AMD: Each CPU supports 12 DDR5 memory channels, 1DPC, up to 24 DIMMs in total
• OCP NIC: 
o Each CPU supports 1* OCP 3.0 NIC, two NICs in total
• Boot drive: 
o 1x M.2 SSD (2280/22110)
o 1x E1.S
CPU Tray Specification



Switch TrayIntroduction
14



15
95 mm
2OU Switch Tray Dimension: 502mm (W) x 95mm (H) x 560mm(D)
Switch Tray Overview



16
8x E1.S
8x OCP NIC 3.0
(TSFF)
USB 3.0 / 2x LEDs
(FIO board)
4x PCIe Switch
FIO board
Switch Tray Front and Top View



17
Item Description
Switch Board
• PCIe switch
o Each PCIe Gen5 switch has 7x16 + 1x4 ports
▪ Two PCIe x16 as uplink
▪ Two PCIe x16 connecting to 2* 400G OCP NIC3.0 TSFF
▪ Two PCIe x16 connecting to two accelerators in accelerator 
baseboard
▪ One PCIe x16 connecting to 4x E1S NVMe SSDs, up to 8TB 
per SSD
▪ One PCIe x4 reserved for accelerator management
o Support hot plug for all SSDs
• OCP NIC 3.0: 
o 8* single port 400G OCP NIC under PCIe switches
Switch Tray Specification



System boards Introduction
18



19
Item Description
DC-SCM 1.0 • Datacenter-ready Secure Control Module (DC-SCM) with a 
standardized Datacenter-ready Secure Control Interface (DC-SCI).
FIO • USB for debug
• 2* LEDs as status indicator
Fan Board • 2* Fan boards, each fan board supports 8* fan modules.
HPDB • Supply 48V power for accelerator tray
VPDB
• 3* 1.3KW Power Bricks for 48V convert to 12V for CPU Tray and 
Switch Tray
• Supply power for fan modules.
System Boards List



20
Board list: Design files:
Design package:
List of Design files contribution



Thank You !
21